(kicad_pcb
	(version 20260206)
	(generator "pcbnew")
	(generator_version "10.0")
	(general
		(thickness 1.6)
		(legacy_teardrops no)
	)
	(paper "A4")
	(title_block
		(title "03242023_DA0F0TMBIJ0_F0T_Motherboard_J_brd_V01_OCP.brd")
		(comment 1 "Grand Teton / footprints 2700-2707 of 6105")
	)
	(layers
		(0 "F.Cu" signal "TOP")
		(4 "In1.Cu" signal "GND")
		(6 "In2.Cu" signal "IN1")
		(8 "In3.Cu" signal "GND1")
		(10 "In4.Cu" signal "IN2")
		(12 "In5.Cu" signal "GND2")
		(14 "In6.Cu" signal "IN3")
		(16 "In7.Cu" signal "GND3")
		(18 "In8.Cu" signal "VCC")
		(20 "In9.Cu" signal "VCC1")
		(22 "In10.Cu" signal "GND4")
		(24 "In11.Cu" signal "IN4")
		(26 "In12.Cu" signal "GND5")
		(28 "In13.Cu" signal "IN5")
		(30 "In14.Cu" signal "GND6")
		(32 "In15.Cu" signal "IN6")
		(34 "In16.Cu" signal "GND7")
		(2 "B.Cu" signal "BOTTOM")
		(9 "F.Adhes" user "F.Adhesive")
		(11 "B.Adhes" user "B.Adhesive")
		(13 "F.Paste" user "Package Geometry/Pastemask Top")
		(15 "B.Paste" user "Package Geometry/Pastemask Bottom")
		(5 "F.SilkS" user "Ref Des/Silkscreen Top")
		(7 "B.SilkS" user "Ref Des/Silkscreen Bottom")
		(1 "F.Mask" user "Board Geometry/Soldermask Top")
		(3 "B.Mask" user "Board Geometry/Soldermask Bottom")
		(17 "Dwgs.User" user "User.Drawings")
		(19 "Cmts.User" user "User.Comments")
		(21 "Eco1.User" user "User.Eco1")
		(23 "Eco2.User" user "User.Eco2")
		(25 "Edge.Cuts" user "Board Geometry/Outline")
		(27 "Margin" user)
		(31 "F.CrtYd" user "Package Geometry/Place Bound Top")
		(29 "B.CrtYd" user "Package Geometry/Place Bound Bottom")
		(35 "F.Fab" user "Ref Des/Assembly Top")
		(33 "B.Fab" user "Ref Des/Assembly Bottom")
	)
	(footprint ""
		(layer "F.Cu")
		(at 12.784582 -410.802836 90)
		(property "Reference" "R2923"
			(at 0 0 90)
			(layer "F.SilkS")
			(hide yes)
			(effects
				(font
					(size 1.27 1.27)
				)
			)
		)
		(property "Value" ""
			(at 0 0 90)
			(layer "F.Fab")
			(effects
				(font
					(size 1.27 1.27)
				)
			)
		)
		(duplicate_pad_numbers_are_jumpers no)
		(fp_line
			(start 0.7874 -0.4064)
			(end 0.7874 0.4064)
			(stroke
				(width 0.1524)
				(type default)
			)
			(layer "F.SilkS")
		)
		(fp_line
			(start -0.7874 -0.4064)
			(end 0.7874 -0.4064)
			(stroke
				(width 0.1524)
				(type default)
			)
			(layer "F.SilkS")
		)
		(fp_line
			(start 0.7874 0.4064)
			(end -0.7874 0.4064)
			(stroke
				(width 0.1524)
				(type default)
			)
			(layer "F.SilkS")
		)
		(fp_line
			(start -0.7874 0.4064)
			(end -0.7874 -0.4064)
			(stroke
				(width 0.1524)
				(type default)
			)
			(layer "F.SilkS")
		)
		(fp_line
			(start -0.12065 -0.305054)
			(end -0.12065 -0.2794)
			(stroke
				(width 0.1)
				(type default)
			)
			(layer "F.Fab")
		)
		(fp_line
			(start -0.67945 -0.305054)
			(end -0.12065 -0.305054)
			(stroke
				(width 0.1)
				(type default)
			)
			(layer "F.Fab")
		)
		(fp_line
			(start 0.67945 -0.3048)
			(end 0.67945 0.3048)
			(stroke
				(width 0.1)
				(type default)
			)
			(layer "F.Fab")
		)
		(fp_line
			(start 0.12065 -0.3048)
			(end 0.67945 -0.3048)
			(stroke
				(width 0.1)
				(type default)
			)
			(layer "F.Fab")
		)
		(fp_line
			(start 0.12065 -0.2794)
			(end 0.12065 -0.3048)
			(stroke
				(width 0.1)
				(type default)
			)
			(layer "F.Fab")
		)
		(fp_line
			(start -0.12065 -0.2794)
			(end 0.12065 -0.2794)
			(stroke
				(width 0.1)
				(type default)
			)
			(layer "F.Fab")
		)
		(fp_line
			(start 0.120396 0.2794)
			(end -0.12065 0.2794)
			(stroke
				(width 0.1)
				(type default)
			)
			(layer "F.Fab")
		)
		(fp_line
			(start -0.12065 0.2794)
			(end -0.12065 0.3048)
			(stroke
				(width 0.1)
				(type default)
			)
			(layer "F.Fab")
		)
		(fp_line
			(start 0.67945 0.3048)
			(end 0.120396 0.3048)
			(stroke
				(width 0.1)
				(type default)
			)
			(layer "F.Fab")
		)
		(fp_line
			(start 0.120396 0.3048)
			(end 0.120396 0.2794)
			(stroke
				(width 0.1)
				(type default)
			)
			(layer "F.Fab")
		)
		(fp_line
			(start -0.12065 0.3048)
			(end -0.67945 0.3048)
			(stroke
				(width 0.1)
				(type default)
			)
			(layer "F.Fab")
		)
		(fp_line
			(start -0.67945 0.3048)
			(end -0.67945 -0.305054)
			(stroke
				(width 0.1)
				(type default)
			)
			(layer "F.Fab")
		)
		(pad "1" smd circle
			(at -0.40005 0 90)
			(size 0 0)
			(layers "F.Cu" "F.Mask" "F.Paste")
			(net "P3V3_AUX")
		)
		(pad "2" smd circle
			(at 0.40005 0 90)
			(size 0 0)
			(layers "F.Cu" "F.Mask" "F.Paste")
			(net "PU_U181_INT")
		)
	)
	(footprint ""
		(layer "F.Cu")
		(at 464.968336 -385.742434 90)
		(property "Reference" "PC1850"
			(at 0 0 90)
			(layer "F.SilkS")
			(hide yes)
			(effects
				(font
					(size 1.27 1.27)
				)
			)
		)
		(property "Value" ""
			(at 0 0 90)
			(layer "F.Fab")
			(effects
				(font
					(size 1.27 1.27)
				)
			)
		)
		(duplicate_pad_numbers_are_jumpers no)
		(fp_line
			(start 1.524 -0.762)
			(end 1.524 0.762)
			(stroke
				(width 0.1524)
				(type default)
			)
			(layer "F.SilkS")
		)
		(fp_line
			(start -1.524 -0.762)
			(end 1.524 -0.762)
			(stroke
				(width 0.1524)
				(type default)
			)
			(layer "F.SilkS")
		)
		(fp_line
			(start 1.524 0.762)
			(end -1.524 0.762)
			(stroke
				(width 0.1524)
				(type default)
			)
			(layer "F.SilkS")
		)
		(fp_line
			(start -1.524 0.762)
			(end -1.524 -0.762)
			(stroke
				(width 0.1524)
				(type default)
			)
			(layer "F.SilkS")
		)
		(fp_line
			(start 1.1049 -0.724916)
			(end -1.1049 -0.724916)
			(stroke
				(width 0.1)
				(type default)
			)
			(layer "F.Fab")
		)
		(fp_line
			(start -1.1049 -0.724916)
			(end -1.1049 0.724916)
			(stroke
				(width 0.1)
				(type default)
			)
			(layer "F.Fab")
		)
		(fp_line
			(start 1.1049 0.724916)
			(end 1.1049 -0.724916)
			(stroke
				(width 0.1)
				(type default)
			)
			(layer "F.Fab")
		)
		(fp_line
			(start -1.1049 0.724916)
			(end 1.1049 0.724916)
			(stroke
				(width 0.1)
				(type default)
			)
			(layer "F.Fab")
		)
		(pad "1" smd rect
			(at -0.889 0 270)
			(size 1.016 1.27)
			(layers "F.Cu" "F.Mask" "F.Paste")
			(net "SW_P5V_AUX_FLT")
		)
		(pad "2" smd rect
			(at 0.889 0 270)
			(size 1.016 1.27)
			(layers "F.Cu" "F.Mask" "F.Paste")
			(net "GND")
		)
	)
	(footprint ""
		(layer "F.Cu")
		(at 145.34388 -57.241948 180)
		(property "Reference" "R2411"
			(at 0 0 180)
			(layer "F.SilkS")
			(hide yes)
			(effects
				(font
					(size 1.27 1.27)
				)
			)
		)
		(property "Value" ""
			(at 0 0 180)
			(layer "F.Fab")
			(effects
				(font
					(size 1.27 1.27)
				)
			)
		)
		(duplicate_pad_numbers_are_jumpers no)
		(fp_line
			(start 0.7874 0.4064)
			(end -0.7874 0.4064)
			(stroke
				(width 0.1524)
				(type default)
			)
			(layer "F.SilkS")
		)
		(fp_line
			(start 0.7874 -0.4064)
			(end 0.7874 0.4064)
			(stroke
				(width 0.1524)
				(type default)
			)
			(layer "F.SilkS")
		)
		(fp_line
			(start -0.7874 0.4064)
			(end -0.7874 -0.4064)
			(stroke
				(width 0.1524)
				(type default)
			)
			(layer "F.SilkS")
		)
		(fp_line
			(start -0.7874 -0.4064)
			(end 0.7874 -0.4064)
			(stroke
				(width 0.1524)
				(type default)
			)
			(layer "F.SilkS")
		)
		(fp_line
			(start 0.67945 0.3048)
			(end 0.120396 0.3048)
			(stroke
				(width 0.1)
				(type default)
			)
			(layer "F.Fab")
		)
		(fp_line
			(start 0.67945 -0.3048)
			(end 0.67945 0.3048)
			(stroke
				(width 0.1)
				(type default)
			)
			(layer "F.Fab")
		)
		(fp_line
			(start 0.12065 -0.2794)
			(end 0.12065 -0.3048)
			(stroke
				(width 0.1)
				(type default)
			)
			(layer "F.Fab")
		)
		(fp_line
			(start 0.12065 -0.3048)
			(end 0.67945 -0.3048)
			(stroke
				(width 0.1)
				(type default)
			)
			(layer "F.Fab")
		)
		(fp_line
			(start 0.120396 0.3048)
			(end 0.120396 0.2794)
			(stroke
				(width 0.1)
				(type default)
			)
			(layer "F.Fab")
		)
		(fp_line
			(start 0.120396 0.2794)
			(end -0.12065 0.2794)
			(stroke
				(width 0.1)
				(type default)
			)
			(layer "F.Fab")
		)
		(fp_line
			(start -0.12065 0.3048)
			(end -0.67945 0.3048)
			(stroke
				(width 0.1)
				(type default)
			)
			(layer "F.Fab")
		)
		(fp_line
			(start -0.12065 0.2794)
			(end -0.12065 0.3048)
			(stroke
				(width 0.1)
				(type default)
			)
			(layer "F.Fab")
		)
		(fp_line
			(start -0.12065 -0.2794)
			(end 0.12065 -0.2794)
			(stroke
				(width 0.1)
				(type default)
			)
			(layer "F.Fab")
		)
		(fp_line
			(start -0.12065 -0.305054)
			(end -0.12065 -0.2794)
			(stroke
				(width 0.1)
				(type default)
			)
			(layer "F.Fab")
		)
		(fp_line
			(start -0.67945 0.3048)
			(end -0.67945 -0.305054)
			(stroke
				(width 0.1)
				(type default)
			)
			(layer "F.Fab")
		)
		(fp_line
			(start -0.67945 -0.305054)
			(end -0.12065 -0.305054)
			(stroke
				(width 0.1)
				(type default)
			)
			(layer "F.Fab")
		)
		(pad "1" smd circle
			(at -0.40005 0 180)
			(size 0 0)
			(layers "F.Cu" "F.Mask" "F.Paste")
			(net "SMB_M2_P0_1V8AUX_SCL_R")
		)
		(pad "2" smd circle
			(at 0.40005 0 180)
			(size 0 0)
			(layers "F.Cu" "F.Mask" "F.Paste")
			(net "SMB_M2_P0_1V8AUX_SCL")
		)
	)
	(footprint ""
		(layer "F.Cu")
		(at 421.92194 -109.271308 90)
		(property "Reference" "PC2162"
			(at 0 0 90)
			(layer "F.SilkS")
			(hide yes)
			(effects
				(font
					(size 1.27 1.27)
				)
			)
		)
		(property "Value" ""
			(at 0 0 90)
			(layer "F.Fab")
			(effects
				(font
					(size 1.27 1.27)
				)
			)
		)
		(duplicate_pad_numbers_are_jumpers no)
		(fp_line
			(start 0.7874 -0.4064)
			(end 0.7874 0.4064)
			(stroke
				(width 0.1524)
				(type default)
			)
			(layer "F.SilkS")
		)
		(fp_line
			(start -0.7874 -0.4064)
			(end 0.7874 -0.4064)
			(stroke
				(width 0.1524)
				(type default)
			)
			(layer "F.SilkS")
		)
		(fp_line
			(start 0.7874 0.4064)
			(end -0.7874 0.4064)
			(stroke
				(width 0.1524)
				(type default)
			)
			(layer "F.SilkS")
		)
		(fp_line
			(start -0.7874 0.4064)
			(end -0.7874 -0.4064)
			(stroke
				(width 0.1524)
				(type default)
			)
			(layer "F.SilkS")
		)
		(fp_line
			(start -0.12065 -0.305054)
			(end -0.12065 -0.2794)
			(stroke
				(width 0.1)
				(type default)
			)
			(layer "F.Fab")
		)
		(fp_line
			(start -0.67945 -0.305054)
			(end -0.12065 -0.305054)
			(stroke
				(width 0.1)
				(type default)
			)
			(layer "F.Fab")
		)
		(fp_line
			(start 0.67945 -0.3048)
			(end 0.67945 0.3048)
			(stroke
				(width 0.1)
				(type default)
			)
			(layer "F.Fab")
		)
		(fp_line
			(start 0.12065 -0.3048)
			(end 0.67945 -0.3048)
			(stroke
				(width 0.1)
				(type default)
			)
			(layer "F.Fab")
		)
		(fp_line
			(start 0.12065 -0.2794)
			(end 0.12065 -0.3048)
			(stroke
				(width 0.1)
				(type default)
			)
			(layer "F.Fab")
		)
		(fp_line
			(start -0.12065 -0.2794)
			(end 0.12065 -0.2794)
			(stroke
				(width 0.1)
				(type default)
			)
			(layer "F.Fab")
		)
		(fp_line
			(start 0.120396 0.2794)
			(end -0.12065 0.2794)
			(stroke
				(width 0.1)
				(type default)
			)
			(layer "F.Fab")
		)
		(fp_line
			(start -0.12065 0.2794)
			(end -0.12065 0.3048)
			(stroke
				(width 0.1)
				(type default)
			)
			(layer "F.Fab")
		)
		(fp_line
			(start 0.67945 0.3048)
			(end 0.120396 0.3048)
			(stroke
				(width 0.1)
				(type default)
			)
			(layer "F.Fab")
		)
		(fp_line
			(start 0.120396 0.3048)
			(end 0.120396 0.2794)
			(stroke
				(width 0.1)
				(type default)
			)
			(layer "F.Fab")
		)
		(fp_line
			(start -0.12065 0.3048)
			(end -0.67945 0.3048)
			(stroke
				(width 0.1)
				(type default)
			)
			(layer "F.Fab")
		)
		(fp_line
			(start -0.67945 0.3048)
			(end -0.67945 -0.305054)
			(stroke
				(width 0.1)
				(type default)
			)
			(layer "F.Fab")
		)
		(pad "1" smd circle
			(at -0.40005 0 90)
			(size 0 0)
			(layers "F.Cu" "F.Mask" "F.Paste")
			(net "P3V3_OCP_GATE_1")
		)
		(pad "2" smd circle
			(at 0.40005 0 90)
			(size 0 0)
			(layers "F.Cu" "F.Mask" "F.Paste")
			(net "GND")
		)
	)
	(footprint ""
		(layer "F.Cu")
		(at 376.271536 -105.483152 90)
		(property "Reference" "R1368"
			(at 0 0 90)
			(layer "F.SilkS")
			(hide yes)
			(effects
				(font
					(size 1.27 1.27)
				)
			)
		)
		(property "Value" ""
			(at 0 0 90)
			(layer "F.Fab")
			(effects
				(font
					(size 1.27 1.27)
				)
			)
		)
		(duplicate_pad_numbers_are_jumpers no)
		(fp_line
			(start 0.7874 -0.4064)
			(end 0.7874 0.4064)
			(stroke
				(width 0.1524)
				(type default)
			)
			(layer "F.SilkS")
		)
		(fp_line
			(start -0.7874 -0.4064)
			(end 0.7874 -0.4064)
			(stroke
				(width 0.1524)
				(type default)
			)
			(layer "F.SilkS")
		)
		(fp_line
			(start 0.7874 0.4064)
			(end -0.7874 0.4064)
			(stroke
				(width 0.1524)
				(type default)
			)
			(layer "F.SilkS")
		)
		(fp_line
			(start -0.7874 0.4064)
			(end -0.7874 -0.4064)
			(stroke
				(width 0.1524)
				(type default)
			)
			(layer "F.SilkS")
		)
		(fp_line
			(start -0.12065 -0.305054)
			(end -0.12065 -0.2794)
			(stroke
				(width 0.1)
				(type default)
			)
			(layer "F.Fab")
		)
		(fp_line
			(start -0.67945 -0.305054)
			(end -0.12065 -0.305054)
			(stroke
				(width 0.1)
				(type default)
			)
			(layer "F.Fab")
		)
		(fp_line
			(start 0.67945 -0.3048)
			(end 0.67945 0.3048)
			(stroke
				(width 0.1)
				(type default)
			)
			(layer "F.Fab")
		)
		(fp_line
			(start 0.12065 -0.3048)
			(end 0.67945 -0.3048)
			(stroke
				(width 0.1)
				(type default)
			)
			(layer "F.Fab")
		)
		(fp_line
			(start 0.12065 -0.2794)
			(end 0.12065 -0.3048)
			(stroke
				(width 0.1)
				(type default)
			)
			(layer "F.Fab")
		)
		(fp_line
			(start -0.12065 -0.2794)
			(end 0.12065 -0.2794)
			(stroke
				(width 0.1)
				(type default)
			)
			(layer "F.Fab")
		)
		(fp_line
			(start 0.120396 0.2794)
			(end -0.12065 0.2794)
			(stroke
				(width 0.1)
				(type default)
			)
			(layer "F.Fab")
		)
		(fp_line
			(start -0.12065 0.2794)
			(end -0.12065 0.3048)
			(stroke
				(width 0.1)
				(type default)
			)
			(layer "F.Fab")
		)
		(fp_line
			(start 0.67945 0.3048)
			(end 0.120396 0.3048)
			(stroke
				(width 0.1)
				(type default)
			)
			(layer "F.Fab")
		)
		(fp_line
			(start 0.120396 0.3048)
			(end 0.120396 0.2794)
			(stroke
				(width 0.1)
				(type default)
			)
			(layer "F.Fab")
		)
		(fp_line
			(start -0.12065 0.3048)
			(end -0.67945 0.3048)
			(stroke
				(width 0.1)
				(type default)
			)
			(layer "F.Fab")
		)
		(fp_line
			(start -0.67945 0.3048)
			(end -0.67945 -0.305054)
			(stroke
				(width 0.1)
				(type default)
			)
			(layer "F.Fab")
		)
		(pad "1" smd circle
			(at -0.40005 0 90)
			(size 0 0)
			(layers "F.Cu" "F.Mask" "F.Paste")
			(net "PD_JTAG_DBP_B2")
		)
		(pad "2" smd circle
			(at 0.40005 0 90)
			(size 0 0)
			(layers "F.Cu" "F.Mask" "F.Paste")
			(net "GND")
		)
	)
	(footprint ""
		(layer "F.Cu")
		(at 132.15874 -115.585748 180)
		(property "Reference" "C1818"
			(at 0 0 180)
			(layer "F.SilkS")
			(hide yes)
			(effects
				(font
					(size 1.27 1.27)
				)
			)
		)
		(property "Value" ""
			(at 0 0 180)
			(layer "F.Fab")
			(effects
				(font
					(size 1.27 1.27)
				)
			)
		)
		(duplicate_pad_numbers_are_jumpers no)
		(fp_line
			(start 0.7874 0.4064)
			(end -0.7874 0.4064)
			(stroke
				(width 0.1524)
				(type default)
			)
			(layer "F.SilkS")
		)
		(fp_line
			(start 0.7874 -0.4064)
			(end 0.7874 0.4064)
			(stroke
				(width 0.1524)
				(type default)
			)
			(layer "F.SilkS")
		)
		(fp_line
			(start -0.7874 0.4064)
			(end -0.7874 -0.4064)
			(stroke
				(width 0.1524)
				(type default)
			)
			(layer "F.SilkS")
		)
		(fp_line
			(start -0.7874 -0.4064)
			(end 0.7874 -0.4064)
			(stroke
				(width 0.1524)
				(type default)
			)
			(layer "F.SilkS")
		)
		(fp_line
			(start 0.67945 0.3048)
			(end 0.120396 0.3048)
			(stroke
				(width 0.1)
				(type default)
			)
			(layer "F.Fab")
		)
		(fp_line
			(start 0.67945 -0.3048)
			(end 0.67945 0.3048)
			(stroke
				(width 0.1)
				(type default)
			)
			(layer "F.Fab")
		)
		(fp_line
			(start 0.12065 -0.2794)
			(end 0.12065 -0.3048)
			(stroke
				(width 0.1)
				(type default)
			)
			(layer "F.Fab")
		)
		(fp_line
			(start 0.12065 -0.3048)
			(end 0.67945 -0.3048)
			(stroke
				(width 0.1)
				(type default)
			)
			(layer "F.Fab")
		)
		(fp_line
			(start 0.120396 0.3048)
			(end 0.120396 0.2794)
			(stroke
				(width 0.1)
				(type default)
			)
			(layer "F.Fab")
		)
		(fp_line
			(start 0.120396 0.2794)
			(end -0.12065 0.2794)
			(stroke
				(width 0.1)
				(type default)
			)
			(layer "F.Fab")
		)
		(fp_line
			(start -0.12065 0.3048)
			(end -0.67945 0.3048)
			(stroke
				(width 0.1)
				(type default)
			)
			(layer "F.Fab")
		)
		(fp_line
			(start -0.12065 0.2794)
			(end -0.12065 0.3048)
			(stroke
				(width 0.1)
				(type default)
			)
			(layer "F.Fab")
		)
		(fp_line
			(start -0.12065 -0.2794)
			(end 0.12065 -0.2794)
			(stroke
				(width 0.1)
				(type default)
			)
			(layer "F.Fab")
		)
		(fp_line
			(start -0.12065 -0.305054)
			(end -0.12065 -0.2794)
			(stroke
				(width 0.1)
				(type default)
			)
			(layer "F.Fab")
		)
		(fp_line
			(start -0.67945 0.3048)
			(end -0.67945 -0.305054)
			(stroke
				(width 0.1)
				(type default)
			)
			(layer "F.Fab")
		)
		(fp_line
			(start -0.67945 -0.305054)
			(end -0.12065 -0.305054)
			(stroke
				(width 0.1)
				(type default)
			)
			(layer "F.Fab")
		)
		(pad "1" smd circle
			(at -0.40005 0 180)
			(size 0 0)
			(layers "F.Cu" "F.Mask" "F.Paste")
			(net "P3V3_AUX")
		)
		(pad "2" smd circle
			(at 0.40005 0 180)
			(size 0 0)
			(layers "F.Cu" "F.Mask" "F.Paste")
			(net "GND")
		)
	)
	(footprint ""
		(layer "F.Cu")
		(at 32.272478 -16.099536 90)
		(property "Reference" "C819"
			(at 0 0 90)
			(layer "F.SilkS")
			(hide yes)
			(effects
				(font
					(size 1.27 1.27)
				)
			)
		)
		(property "Value" ""
			(at 0 0 90)
			(layer "F.Fab")
			(effects
				(font
					(size 1.27 1.27)
				)
			)
		)
		(duplicate_pad_numbers_are_jumpers no)
		(fp_line
			(start 0.299974 -0.150114)
			(end 0.299974 0.150114)
			(stroke
				(width 0.1)
				(type default)
			)
			(layer "F.Fab")
		)
		(fp_line
			(start -0.299974 -0.150114)
			(end 0.299974 -0.150114)
			(stroke
				(width 0.1)
				(type default)
			)
			(layer "F.Fab")
		)
		(fp_line
			(start 0.299974 0.150114)
			(end -0.299974 0.150114)
			(stroke
				(width 0.1)
				(type default)
			)
			(layer "F.Fab")
		)
		(fp_line
			(start -0.299974 0.150114)
			(end -0.299974 -0.150114)
			(stroke
				(width 0.1)
				(type default)
			)
			(layer "F.Fab")
		)
		(pad "1" smd rect
			(at -0.2667 0 90)
			(size 0.3048 0.381)
			(layers "F.Cu" "F.Mask" "F.Paste")
			(net "P5E_CPU1_PE1_TX_C_DP<9>")
		)
		(pad "2" smd rect
			(at 0.2667 0 90)
			(size 0.3048 0.381)
			(layers "F.Cu" "F.Mask" "F.Paste")
			(net "P5E_CPU1_PE1_TX_DP<9>")
		)
	)
	(footprint ""
		(layer "F.Cu")
		(at 163.014914 -402.371052 -90)
		(property "Reference" "C771"
			(at 0 0 270)
			(layer "F.SilkS")
			(hide yes)
			(effects
				(font
					(size 1.27 1.27)
				)
			)
		)
		(property "Value" ""
			(at 0 0 270)
			(layer "F.Fab")
			(effects
				(font
					(size 1.27 1.27)
				)
			)
		)
		(duplicate_pad_numbers_are_jumpers no)
		(fp_line
			(start -0.299974 0.150114)
			(end -0.299974 -0.150114)
			(stroke
				(width 0.1)
				(type default)
			)
			(layer "F.Fab")
		)
		(fp_line
			(start 0.299974 0.150114)
			(end -0.299974 0.150114)
			(stroke
				(width 0.1)
				(type default)
			)
			(layer "F.Fab")
		)
		(fp_line
			(start -0.299974 -0.150114)
			(end 0.299974 -0.150114)
			(stroke
				(width 0.1)
				(type default)
			)
			(layer "F.Fab")
		)
		(fp_line
			(start 0.299974 -0.150114)
			(end 0.299974 0.150114)
			(stroke
				(width 0.1)
				(type default)
			)
			(layer "F.Fab")
		)
		(pad "1" smd rect
			(at -0.2667 0 270)
			(size 0.3048 0.381)
			(layers "F.Cu" "F.Mask" "F.Paste")
			(net "P5E_CPU1_PE2_TX_C_DP<1>")
		)
		(pad "2" smd rect
			(at 0.2667 0 270)
			(size 0.3048 0.381)
			(layers "F.Cu" "F.Mask" "F.Paste")
			(net "P5E_CPU1_PE2_TX_DP<1>")
		)
	)
)
